(kicad_pcb
	(version 20260206)
	(generator "pcbnew")
	(generator_version "10.0")
	(general
		(thickness 1.6)
		(legacy_teardrops no)
	)
	(paper "A4")
	(title_block
		(title "03242023_DA0F0TMBIJ0_F0T_Motherboard_J_brd_V01_OCP.brd")
		(comment 1 "Grand Teton / footprint 3900 of 6105 (J31), pads 225-291 of 291")
	)
	(layers
		(0 "F.Cu" signal "TOP")
		(4 "In1.Cu" signal "GND")
		(6 "In2.Cu" signal "IN1")
		(8 "In3.Cu" signal "GND1")
		(10 "In4.Cu" signal "IN2")
		(12 "In5.Cu" signal "GND2")
		(14 "In6.Cu" signal "IN3")
		(16 "In7.Cu" signal "GND3")
		(18 "In8.Cu" signal "VCC")
		(20 "In9.Cu" signal "VCC1")
		(22 "In10.Cu" signal "GND4")
		(24 "In11.Cu" signal "IN4")
		(26 "In12.Cu" signal "GND5")
		(28 "In13.Cu" signal "IN5")
		(30 "In14.Cu" signal "GND6")
		(32 "In15.Cu" signal "IN6")
		(34 "In16.Cu" signal "GND7")
		(2 "B.Cu" signal "BOTTOM")
		(9 "F.Adhes" user "F.Adhesive")
		(11 "B.Adhes" user "B.Adhesive")
		(13 "F.Paste" user "Package Geometry/Pastemask Top")
		(15 "B.Paste" user "Package Geometry/Pastemask Bottom")
		(5 "F.SilkS" user "Ref Des/Silkscreen Top")
		(7 "B.SilkS" user "Ref Des/Silkscreen Bottom")
		(1 "F.Mask" user "Board Geometry/Soldermask Top")
		(3 "B.Mask" user "Board Geometry/Soldermask Bottom")
		(17 "Dwgs.User" user "User.Drawings")
		(19 "Cmts.User" user "User.Comments")
		(21 "Eco1.User" user "User.Eco1")
		(23 "Eco2.User" user "User.Eco2")
		(25 "Edge.Cuts" user "Board Geometry/Outline")
		(27 "Margin" user)
		(31 "F.CrtYd" user "Package Geometry/Place Bound Top")
		(29 "B.CrtYd" user "Package Geometry/Place Bound Bottom")
		(35 "F.Fab" user "Ref Des/Assembly Top")
		(33 "B.Fab" user "Ref Des/Assembly Bottom")
	)
	(footprint ""
		(layer "F.Cu")
		(at 213.66988 -258.091686)
		(property "Reference" "J31"
			(at -3.683 -81.702148 0)
			(unlocked yes)
			(layer "F.SilkS")
			(effects
				(font
					(size 0.7874 0.5842)
					(thickness 0.1524)
				)
				(justify left)
			)
		)
		(property "Value" ""
			(at 0 0 0)
			(layer "F.Fab")
			(effects
				(font
					(size 1.27 1.27)
				)
			)
		)
		(duplicate_pad_numbers_are_jumpers no)
		(pad "225" smd rect
			(at 2.050034 9.774936 270)
			(size 0.519938 1.4986)
			(layers "F.Cu" "F.Mask" "F.Paste")
			(net "M_H_CPU1_SB_CA<5>")
		)
		(pad "226" smd rect
			(at 2.050034 10.625074 270)
			(size 0.519938 1.4986)
			(layers "F.Cu" "F.Mask" "F.Paste")
			(net "GND")
		)
		(pad "227" smd rect
			(at 2.050034 11.474958 270)
			(size 0.519938 1.4986)
			(layers "F.Cu" "F.Mask" "F.Paste")
			(net "M_H_CPU1_SB_PAR")
		)
		(pad "228" smd rect
			(at 2.050034 12.325096 270)
			(size 0.519938 1.4986)
			(layers "F.Cu" "F.Mask" "F.Paste")
			(net "GND")
		)
		(pad "229" smd rect
			(at 2.050034 13.17498 270)
			(size 0.519938 1.4986)
			(layers "F.Cu" "F.Mask" "F.Paste")
			(net "M_H_CPU1_SB_CS_N<1>")
		)
		(pad "230" smd rect
			(at 2.050034 14.025118 270)
			(size 0.519938 1.4986)
			(layers "F.Cu" "F.Mask" "F.Paste")
			(net "GND")
		)
		(pad "231" smd rect
			(at 2.050034 14.875002 270)
			(size 0.519938 1.4986)
			(layers "F.Cu" "F.Mask" "F.Paste")
			(net "TP_CHH_CPU1_DIMM1_FRU_5")
		)
		(pad "232" smd rect
			(at 2.050034 15.724886 270)
			(size 0.519938 1.4986)
			(layers "F.Cu" "F.Mask" "F.Paste")
			(net "TP_CHH_CPU1_DIMM1_FRU_6")
		)
		(pad "233" smd rect
			(at 2.050034 16.575024 270)
			(size 0.519938 1.4986)
			(layers "F.Cu" "F.Mask" "F.Paste")
			(net "GND")
		)
		(pad "234" smd rect
			(at 2.050034 17.424908 270)
			(size 0.519938 1.4986)
			(layers "F.Cu" "F.Mask" "F.Paste")
			(net "M_H_CPU1_SB_CB<6>")
		)
		(pad "235" smd rect
			(at 2.050034 18.275046 270)
			(size 0.519938 1.4986)
			(layers "F.Cu" "F.Mask" "F.Paste")
			(net "GND")
		)
		(pad "236" smd rect
			(at 2.050034 19.12493 270)
			(size 0.519938 1.4986)
			(layers "F.Cu" "F.Mask" "F.Paste")
			(net "M_H_CPU1_SB_CB<7>")
		)
		(pad "237" smd rect
			(at 2.050034 19.975068 270)
			(size 0.519938 1.4986)
			(layers "F.Cu" "F.Mask" "F.Paste")
			(net "GND")
		)
		(pad "238" smd rect
			(at 2.050034 20.824952 270)
			(size 0.519938 1.4986)
			(layers "F.Cu" "F.Mask" "F.Paste")
			(net "M_H_CPU1_SB_DQS_DN<4>")
		)
		(pad "239" smd rect
			(at 2.050034 21.67509 270)
			(size 0.519938 1.4986)
			(layers "F.Cu" "F.Mask" "F.Paste")
			(net "M_H_CPU1_SB_DQS_DP<4>")
		)
		(pad "240" smd rect
			(at 2.050034 22.524974 270)
			(size 0.519938 1.4986)
			(layers "F.Cu" "F.Mask" "F.Paste")
			(net "GND")
		)
		(pad "241" smd rect
			(at 2.050034 23.375112 270)
			(size 0.519938 1.4986)
			(layers "F.Cu" "F.Mask" "F.Paste")
			(net "M_H_CPU1_SB_CB<2>")
		)
		(pad "242" smd rect
			(at 2.050034 24.224996 270)
			(size 0.519938 1.4986)
			(layers "F.Cu" "F.Mask" "F.Paste")
			(net "GND")
		)
		(pad "243" smd rect
			(at 2.050034 25.07488 270)
			(size 0.519938 1.4986)
			(layers "F.Cu" "F.Mask" "F.Paste")
			(net "M_H_CPU1_SB_CB<3>")
		)
		(pad "244" smd rect
			(at 2.050034 25.925018 270)
			(size 0.519938 1.4986)
			(layers "F.Cu" "F.Mask" "F.Paste")
			(net "GND")
		)
		(pad "245" smd rect
			(at 2.050034 26.774902 270)
			(size 0.519938 1.4986)
			(layers "F.Cu" "F.Mask" "F.Paste")
			(net "M_H_CPU1_SB_DQ<2>")
		)
		(pad "246" smd rect
			(at 2.050034 27.62504 270)
			(size 0.519938 1.4986)
			(layers "F.Cu" "F.Mask" "F.Paste")
			(net "GND")
		)
		(pad "247" smd rect
			(at 2.050034 28.474924 270)
			(size 0.519938 1.4986)
			(layers "F.Cu" "F.Mask" "F.Paste")
			(net "M_H_CPU1_SB_DQ<3>")
		)
		(pad "248" smd rect
			(at 2.050034 29.325062 270)
			(size 0.519938 1.4986)
			(layers "F.Cu" "F.Mask" "F.Paste")
			(net "GND")
		)
		(pad "249" smd rect
			(at 2.050034 30.174946 270)
			(size 0.519938 1.4986)
			(layers "F.Cu" "F.Mask" "F.Paste")
			(net "M_H_CPU1_SB_DQS_DN<5>")
		)
		(pad "250" smd rect
			(at 2.050034 31.025084 270)
			(size 0.519938 1.4986)
			(layers "F.Cu" "F.Mask" "F.Paste")
			(net "M_H_CPU1_SB_DQS_DP<5>")
		)
		(pad "251" smd rect
			(at 2.050034 31.874968 270)
			(size 0.519938 1.4986)
			(layers "F.Cu" "F.Mask" "F.Paste")
			(net "GND")
		)
		(pad "252" smd rect
			(at 2.050034 32.725106 270)
			(size 0.519938 1.4986)
			(layers "F.Cu" "F.Mask" "F.Paste")
			(net "M_H_CPU1_SB_DQ<6>")
		)
		(pad "253" smd rect
			(at 2.050034 33.57499 270)
			(size 0.519938 1.4986)
			(layers "F.Cu" "F.Mask" "F.Paste")
			(net "GND")
		)
		(pad "254" smd rect
			(at 2.050034 34.425128 270)
			(size 0.519938 1.4986)
			(layers "F.Cu" "F.Mask" "F.Paste")
			(net "M_H_CPU1_SB_DQ<7>")
		)
		(pad "255" smd rect
			(at 2.050034 35.275012 270)
			(size 0.519938 1.4986)
			(layers "F.Cu" "F.Mask" "F.Paste")
			(net "GND")
		)
		(pad "256" smd rect
			(at 2.050034 36.124896 270)
			(size 0.519938 1.4986)
			(layers "F.Cu" "F.Mask" "F.Paste")
			(net "M_H_CPU1_SB_DQ<10>")
		)
		(pad "257" smd rect
			(at 2.050034 36.975034 270)
			(size 0.519938 1.4986)
			(layers "F.Cu" "F.Mask" "F.Paste")
			(net "GND")
		)
		(pad "258" smd rect
			(at 2.050034 37.824918 270)
			(size 0.519938 1.4986)
			(layers "F.Cu" "F.Mask" "F.Paste")
			(net "M_H_CPU1_SB_DQ<11>")
		)
		(pad "259" smd rect
			(at 2.050034 38.675056 270)
			(size 0.519938 1.4986)
			(layers "F.Cu" "F.Mask" "F.Paste")
			(net "GND")
		)
		(pad "260" smd rect
			(at 2.050034 39.52494 270)
			(size 0.519938 1.4986)
			(layers "F.Cu" "F.Mask" "F.Paste")
			(net "M_H_CPU1_SB_DQS_DN<6>")
		)
		(pad "261" smd rect
			(at 2.050034 40.375078 270)
			(size 0.519938 1.4986)
			(layers "F.Cu" "F.Mask" "F.Paste")
			(net "M_H_CPU1_SB_DQS_DP<6>")
		)
		(pad "262" smd rect
			(at 2.050034 41.224962 270)
			(size 0.519938 1.4986)
			(layers "F.Cu" "F.Mask" "F.Paste")
			(net "GND")
		)
		(pad "263" smd rect
			(at 2.050034 42.0751 270)
			(size 0.519938 1.4986)
			(layers "F.Cu" "F.Mask" "F.Paste")
			(net "M_H_CPU1_SB_DQ<14>")
		)
		(pad "264" smd rect
			(at 2.050034 42.924984 270)
			(size 0.519938 1.4986)
			(layers "F.Cu" "F.Mask" "F.Paste")
			(net "GND")
		)
		(pad "265" smd rect
			(at 2.050034 43.775122 270)
			(size 0.519938 1.4986)
			(layers "F.Cu" "F.Mask" "F.Paste")
			(net "M_H_CPU1_SB_DQ<15>")
		)
		(pad "266" smd rect
			(at 2.050034 44.625006 270)
			(size 0.519938 1.4986)
			(layers "F.Cu" "F.Mask" "F.Paste")
			(net "GND")
		)
		(pad "267" smd rect
			(at 2.050034 45.47489 270)
			(size 0.519938 1.4986)
			(layers "F.Cu" "F.Mask" "F.Paste")
			(net "M_H_CPU1_SB_DQ<18>")
		)
		(pad "268" smd rect
			(at 2.050034 46.325028 270)
			(size 0.519938 1.4986)
			(layers "F.Cu" "F.Mask" "F.Paste")
			(net "GND")
		)
		(pad "269" smd rect
			(at 2.050034 47.174912 270)
			(size 0.519938 1.4986)
			(layers "F.Cu" "F.Mask" "F.Paste")
			(net "M_H_CPU1_SB_DQ<19>")
		)
		(pad "270" smd rect
			(at 2.050034 48.02505 270)
			(size 0.519938 1.4986)
			(layers "F.Cu" "F.Mask" "F.Paste")
			(net "GND")
		)
		(pad "271" smd rect
			(at 2.050034 48.874934 270)
			(size 0.519938 1.4986)
			(layers "F.Cu" "F.Mask" "F.Paste")
			(net "M_H_CPU1_SB_DQS_DN<7>")
		)
		(pad "272" smd rect
			(at 2.050034 49.725072 270)
			(size 0.519938 1.4986)
			(layers "F.Cu" "F.Mask" "F.Paste")
			(net "M_H_CPU1_SB_DQS_DP<7>")
		)
		(pad "273" smd rect
			(at 2.050034 50.574956 270)
			(size 0.519938 1.4986)
			(layers "F.Cu" "F.Mask" "F.Paste")
			(net "GND")
		)
		(pad "274" smd rect
			(at 2.050034 51.425094 270)
			(size 0.519938 1.4986)
			(layers "F.Cu" "F.Mask" "F.Paste")
			(net "M_H_CPU1_SB_DQ<22>")
		)
		(pad "275" smd rect
			(at 2.050034 52.274978 270)
			(size 0.519938 1.4986)
			(layers "F.Cu" "F.Mask" "F.Paste")
			(net "GND")
		)
		(pad "276" smd rect
			(at 2.050034 53.125116 270)
			(size 0.519938 1.4986)
			(layers "F.Cu" "F.Mask" "F.Paste")
			(net "M_H_CPU1_SB_DQ<23>")
		)
		(pad "277" smd rect
			(at 2.050034 53.975 270)
			(size 0.519938 1.4986)
			(layers "F.Cu" "F.Mask" "F.Paste")
			(net "GND")
		)
		(pad "278" smd rect
			(at 2.050034 54.824884 270)
			(size 0.519938 1.4986)
			(layers "F.Cu" "F.Mask" "F.Paste")
			(net "M_H_CPU1_SB_DQ<26>")
		)
		(pad "279" smd rect
			(at 2.050034 55.675022 270)
			(size 0.519938 1.4986)
			(layers "F.Cu" "F.Mask" "F.Paste")
			(net "GND")
		)
		(pad "280" smd rect
			(at 2.050034 56.524906 270)
			(size 0.519938 1.4986)
			(layers "F.Cu" "F.Mask" "F.Paste")
			(net "M_H_CPU1_SB_DQ<27>")
		)
		(pad "281" smd rect
			(at 2.050034 57.375044 270)
			(size 0.519938 1.4986)
			(layers "F.Cu" "F.Mask" "F.Paste")
			(net "GND")
		)
		(pad "282" smd rect
			(at 2.050034 58.224928 270)
			(size 0.519938 1.4986)
			(layers "F.Cu" "F.Mask" "F.Paste")
			(net "M_H_CPU1_SB_DQS_DN<8>")
		)
		(pad "283" smd rect
			(at 2.050034 59.075066 270)
			(size 0.519938 1.4986)
			(layers "F.Cu" "F.Mask" "F.Paste")
			(net "M_H_CPU1_SB_DQS_DP<8>")
		)
		(pad "284" smd rect
			(at 2.050034 59.92495 270)
			(size 0.519938 1.4986)
			(layers "F.Cu" "F.Mask" "F.Paste")
			(net "GND")
		)
		(pad "285" smd rect
			(at 2.050034 60.775088 270)
			(size 0.519938 1.4986)
			(layers "F.Cu" "F.Mask" "F.Paste")
			(net "M_H_CPU1_SB_DQ<30>")
		)
		(pad "286" smd rect
			(at 2.050034 61.624972 270)
			(size 0.519938 1.4986)
			(layers "F.Cu" "F.Mask" "F.Paste")
			(net "GND")
		)
		(pad "287" smd rect
			(at 2.050034 62.47511 270)
			(size 0.519938 1.4986)
			(layers "F.Cu" "F.Mask" "F.Paste")
			(net "M_H_CPU1_SB_DQ<31>")
		)
		(pad "288" smd rect
			(at 2.050034 63.324994 270)
			(size 0.519938 1.4986)
			(layers "F.Cu" "F.Mask" "F.Paste")
			(net "GND")
		)
		(pad "G1" thru_hole oval
			(at 0 -68.97497)
			(size 2.8194 1.5748)
			(drill oval 2.4384 1.1938)
			(layers "*.Cu" "*.Mask")
			(remove_unused_layers no)
			(net "GND")
			(clearance 0.127)
			(thermal_gap 0.127)
		)
		(pad "G2" thru_hole oval
			(at 0 3.875024)
			(size 2.8194 1.5748)
			(drill oval 2.4384 1.1938)
			(layers "*.Cu" "*.Mask")
			(remove_unused_layers no)
			(net "GND")
			(clearance 0.127)
			(thermal_gap 0.127)
		)
		(pad "G3" thru_hole oval
			(at 0 68.97497)
			(size 2.8194 1.5748)
			(drill oval 2.4384 1.1938)
			(layers "*.Cu" "*.Mask")
			(remove_unused_layers no)
			(net "GND")
			(clearance 0.127)
			(thermal_gap 0.127)
		)
	)
)
